(kicad_pcb
	(version 20260206)
	(generator "pcbnew")
	(generator_version "10.0")
	(general
		(thickness 1.6)
		(legacy_teardrops no)
	)
	(paper "A4")
	(title_block
		(title "01162023_DA0F0TEBIF0_F0T_Expander_BD_F_brd_V02_OCP.brd")
		(comment 1 "Grand Teton / footprints 1361-1366 of 9728")
	)
	(layers
		(0 "F.Cu" signal "TOP")
		(4 "In1.Cu" signal "GND")
		(6 "In2.Cu" signal "VCC")
		(8 "In3.Cu" signal "VCC1")
		(10 "In4.Cu" signal "GND1")
		(12 "In5.Cu" signal "IN1")
		(14 "In6.Cu" signal "GND2")
		(16 "In7.Cu" signal "IN2")
		(18 "In8.Cu" signal "GND3")
		(20 "In9.Cu" signal "IN3")
		(22 "In10.Cu" signal "GND4")
		(24 "In11.Cu" signal "IN4")
		(26 "In12.Cu" signal "GND5")
		(28 "In13.Cu" signal "IN5")
		(30 "In14.Cu" signal "GND6")
		(32 "In15.Cu" signal "IN6")
		(34 "In16.Cu" signal "GND7")
		(2 "B.Cu" signal "BOTTOM")
		(9 "F.Adhes" user "F.Adhesive")
		(11 "B.Adhes" user "B.Adhesive")
		(13 "F.Paste" user "Package Geometry/Pastemask Top")
		(15 "B.Paste" user "Package Geometry/Pastemask Bottom")
		(5 "F.SilkS" user "Ref Des/Silkscreen Top")
		(7 "B.SilkS" user "Ref Des/Silkscreen Bottom")
		(1 "F.Mask" user "Board Geometry/Soldermask Top")
		(3 "B.Mask" user "Board Geometry/Soldermask Bottom")
		(17 "Dwgs.User" user "User.Drawings")
		(19 "Cmts.User" user "User.Comments")
		(21 "Eco1.User" user "User.Eco1")
		(23 "Eco2.User" user "User.Eco2")
		(25 "Edge.Cuts" user "Board Geometry/Outline")
		(27 "Margin" user)
		(31 "F.CrtYd" user "Package Geometry/Place Bound Top")
		(29 "B.CrtYd" user "Package Geometry/Place Bound Bottom")
		(35 "F.Fab" user "Ref Des/Assembly Top")
		(33 "B.Fab" user "Ref Des/Assembly Bottom")
	)
	(footprint ""
		(layer "F.Cu")
		(at 161.59861 -66.32194 -90)
		(property "Reference" "PC843"
			(at 0 0 270)
			(layer "F.SilkS")
			(hide yes)
			(effects
				(font
					(size 1.27 1.27)
				)
			)
		)
		(property "Value" ""
			(at 0 0 270)
			(layer "F.Fab")
			(effects
				(font
					(size 1.27 1.27)
				)
			)
		)
		(duplicate_pad_numbers_are_jumpers no)
		(fp_line
			(start -0.7874 0.4064)
			(end -0.7874 -0.4064)
			(stroke
				(width 0.1524)
				(type default)
			)
			(layer "F.SilkS")
		)
		(fp_line
			(start 0.7874 0.4064)
			(end -0.7874 0.4064)
			(stroke
				(width 0.1524)
				(type default)
			)
			(layer "F.SilkS")
		)
		(fp_line
			(start -0.7874 -0.4064)
			(end 0.7874 -0.4064)
			(stroke
				(width 0.1524)
				(type default)
			)
			(layer "F.SilkS")
		)
		(fp_line
			(start 0.7874 -0.4064)
			(end 0.7874 0.4064)
			(stroke
				(width 0.1524)
				(type default)
			)
			(layer "F.SilkS")
		)
		(fp_line
			(start -0.67945 0.3048)
			(end -0.67945 -0.305054)
			(stroke
				(width 0.1)
				(type default)
			)
			(layer "F.Fab")
		)
		(fp_line
			(start -0.12065 0.3048)
			(end -0.67945 0.3048)
			(stroke
				(width 0.1)
				(type default)
			)
			(layer "F.Fab")
		)
		(fp_line
			(start 0.120396 0.3048)
			(end 0.120396 0.2794)
			(stroke
				(width 0.1)
				(type default)
			)
			(layer "F.Fab")
		)
		(fp_line
			(start 0.67945 0.3048)
			(end 0.120396 0.3048)
			(stroke
				(width 0.1)
				(type default)
			)
			(layer "F.Fab")
		)
		(fp_line
			(start -0.12065 0.2794)
			(end -0.12065 0.3048)
			(stroke
				(width 0.1)
				(type default)
			)
			(layer "F.Fab")
		)
		(fp_line
			(start 0.120396 0.2794)
			(end -0.12065 0.2794)
			(stroke
				(width 0.1)
				(type default)
			)
			(layer "F.Fab")
		)
		(fp_line
			(start -0.12065 -0.2794)
			(end 0.12065 -0.2794)
			(stroke
				(width 0.1)
				(type default)
			)
			(layer "F.Fab")
		)
		(fp_line
			(start 0.12065 -0.2794)
			(end 0.12065 -0.3048)
			(stroke
				(width 0.1)
				(type default)
			)
			(layer "F.Fab")
		)
		(fp_line
			(start 0.12065 -0.3048)
			(end 0.67945 -0.3048)
			(stroke
				(width 0.1)
				(type default)
			)
			(layer "F.Fab")
		)
		(fp_line
			(start 0.67945 -0.3048)
			(end 0.67945 0.3048)
			(stroke
				(width 0.1)
				(type default)
			)
			(layer "F.Fab")
		)
		(fp_line
			(start -0.67945 -0.305054)
			(end -0.12065 -0.305054)
			(stroke
				(width 0.1)
				(type default)
			)
			(layer "F.Fab")
		)
		(fp_line
			(start -0.12065 -0.305054)
			(end -0.12065 -0.2794)
			(stroke
				(width 0.1)
				(type default)
			)
			(layer "F.Fab")
		)
		(pad "1" smd circle
			(at -0.40005 0 270)
			(size 0 0)
			(layers "F.Cu" "F.Mask" "F.Paste")
			(net "P12V_SSD5_CO_GATE")
		)
		(pad "2" smd circle
			(at 0.40005 0 270)
			(size 0 0)
			(layers "F.Cu" "F.Mask" "F.Paste")
			(net "GND")
		)
	)
	(footprint ""
		(layer "F.Cu")
		(at 150.22068 -26.666444 -90)
		(property "Reference" "R4063"
			(at 0 0 270)
			(layer "F.SilkS")
			(hide yes)
			(effects
				(font
					(size 1.27 1.27)
				)
			)
		)
		(property "Value" ""
			(at 0 0 270)
			(layer "F.Fab")
			(effects
				(font
					(size 1.27 1.27)
				)
			)
		)
		(duplicate_pad_numbers_are_jumpers no)
		(fp_line
			(start -0.7874 0.4064)
			(end -0.7874 -0.4064)
			(stroke
				(width 0.1524)
				(type default)
			)
			(layer "F.SilkS")
		)
		(fp_line
			(start 0.7874 0.4064)
			(end -0.7874 0.4064)
			(stroke
				(width 0.1524)
				(type default)
			)
			(layer "F.SilkS")
		)
		(fp_line
			(start -0.7874 -0.4064)
			(end 0.7874 -0.4064)
			(stroke
				(width 0.1524)
				(type default)
			)
			(layer "F.SilkS")
		)
		(fp_line
			(start 0.7874 -0.4064)
			(end 0.7874 0.4064)
			(stroke
				(width 0.1524)
				(type default)
			)
			(layer "F.SilkS")
		)
		(fp_line
			(start -0.67945 0.3048)
			(end -0.67945 -0.305054)
			(stroke
				(width 0.1)
				(type default)
			)
			(layer "F.Fab")
		)
		(fp_line
			(start -0.12065 0.3048)
			(end -0.67945 0.3048)
			(stroke
				(width 0.1)
				(type default)
			)
			(layer "F.Fab")
		)
		(fp_line
			(start 0.120396 0.3048)
			(end 0.120396 0.2794)
			(stroke
				(width 0.1)
				(type default)
			)
			(layer "F.Fab")
		)
		(fp_line
			(start 0.67945 0.3048)
			(end 0.120396 0.3048)
			(stroke
				(width 0.1)
				(type default)
			)
			(layer "F.Fab")
		)
		(fp_line
			(start -0.12065 0.2794)
			(end -0.12065 0.3048)
			(stroke
				(width 0.1)
				(type default)
			)
			(layer "F.Fab")
		)
		(fp_line
			(start 0.120396 0.2794)
			(end -0.12065 0.2794)
			(stroke
				(width 0.1)
				(type default)
			)
			(layer "F.Fab")
		)
		(fp_line
			(start -0.12065 -0.2794)
			(end 0.12065 -0.2794)
			(stroke
				(width 0.1)
				(type default)
			)
			(layer "F.Fab")
		)
		(fp_line
			(start 0.12065 -0.2794)
			(end 0.12065 -0.3048)
			(stroke
				(width 0.1)
				(type default)
			)
			(layer "F.Fab")
		)
		(fp_line
			(start 0.12065 -0.3048)
			(end 0.67945 -0.3048)
			(stroke
				(width 0.1)
				(type default)
			)
			(layer "F.Fab")
		)
		(fp_line
			(start 0.67945 -0.3048)
			(end 0.67945 0.3048)
			(stroke
				(width 0.1)
				(type default)
			)
			(layer "F.Fab")
		)
		(fp_line
			(start -0.67945 -0.305054)
			(end -0.12065 -0.305054)
			(stroke
				(width 0.1)
				(type default)
			)
			(layer "F.Fab")
		)
		(fp_line
			(start -0.12065 -0.305054)
			(end -0.12065 -0.2794)
			(stroke
				(width 0.1)
				(type default)
			)
			(layer "F.Fab")
		)
		(pad "1" smd circle
			(at -0.40005 0 270)
			(size 0 0)
			(layers "F.Cu" "F.Mask" "F.Paste")
			(net "PRSNT_SSD5_R_N")
		)
		(pad "2" smd circle
			(at 0.40005 0 270)
			(size 0 0)
			(layers "F.Cu" "F.Mask" "F.Paste")
			(net "PRSNT_SSD5_N")
		)
	)
	(footprint ""
		(layer "F.Cu")
		(at 345.059 -234.061 -90)
		(property "Reference" "R3552"
			(at 0 0 270)
			(layer "F.SilkS")
			(hide yes)
			(effects
				(font
					(size 1.27 1.27)
				)
			)
		)
		(property "Value" ""
			(at 0 0 270)
			(layer "F.Fab")
			(effects
				(font
					(size 1.27 1.27)
				)
			)
		)
		(duplicate_pad_numbers_are_jumpers no)
		(fp_line
			(start -0.7874 0.4064)
			(end -0.7874 -0.4064)
			(stroke
				(width 0.1524)
				(type default)
			)
			(layer "F.SilkS")
		)
		(fp_line
			(start 0.7874 0.4064)
			(end -0.7874 0.4064)
			(stroke
				(width 0.1524)
				(type default)
			)
			(layer "F.SilkS")
		)
		(fp_line
			(start -0.7874 -0.4064)
			(end 0.7874 -0.4064)
			(stroke
				(width 0.1524)
				(type default)
			)
			(layer "F.SilkS")
		)
		(fp_line
			(start 0.7874 -0.4064)
			(end 0.7874 0.4064)
			(stroke
				(width 0.1524)
				(type default)
			)
			(layer "F.SilkS")
		)
		(fp_line
			(start -0.67945 0.3048)
			(end -0.67945 -0.305054)
			(stroke
				(width 0.1)
				(type default)
			)
			(layer "F.Fab")
		)
		(fp_line
			(start -0.12065 0.3048)
			(end -0.67945 0.3048)
			(stroke
				(width 0.1)
				(type default)
			)
			(layer "F.Fab")
		)
		(fp_line
			(start 0.120396 0.3048)
			(end 0.120396 0.2794)
			(stroke
				(width 0.1)
				(type default)
			)
			(layer "F.Fab")
		)
		(fp_line
			(start 0.67945 0.3048)
			(end 0.120396 0.3048)
			(stroke
				(width 0.1)
				(type default)
			)
			(layer "F.Fab")
		)
		(fp_line
			(start -0.12065 0.2794)
			(end -0.12065 0.3048)
			(stroke
				(width 0.1)
				(type default)
			)
			(layer "F.Fab")
		)
		(fp_line
			(start 0.120396 0.2794)
			(end -0.12065 0.2794)
			(stroke
				(width 0.1)
				(type default)
			)
			(layer "F.Fab")
		)
		(fp_line
			(start -0.12065 -0.2794)
			(end 0.12065 -0.2794)
			(stroke
				(width 0.1)
				(type default)
			)
			(layer "F.Fab")
		)
		(fp_line
			(start 0.12065 -0.2794)
			(end 0.12065 -0.3048)
			(stroke
				(width 0.1)
				(type default)
			)
			(layer "F.Fab")
		)
		(fp_line
			(start 0.12065 -0.3048)
			(end 0.67945 -0.3048)
			(stroke
				(width 0.1)
				(type default)
			)
			(layer "F.Fab")
		)
		(fp_line
			(start 0.67945 -0.3048)
			(end 0.67945 0.3048)
			(stroke
				(width 0.1)
				(type default)
			)
			(layer "F.Fab")
		)
		(fp_line
			(start -0.67945 -0.305054)
			(end -0.12065 -0.305054)
			(stroke
				(width 0.1)
				(type default)
			)
			(layer "F.Fab")
		)
		(fp_line
			(start -0.12065 -0.305054)
			(end -0.12065 -0.2794)
			(stroke
				(width 0.1)
				(type default)
			)
			(layer "F.Fab")
		)
		(pad "1" smd circle
			(at -0.40005 0 270)
			(size 0 0)
			(layers "F.Cu" "F.Mask" "F.Paste")
			(net "SSD4_PWRDIS_R")
		)
		(pad "2" smd circle
			(at 0.40005 0 270)
			(size 0 0)
			(layers "F.Cu" "F.Mask" "F.Paste")
			(net "SSD4_PWRDIS")
		)
	)
	(footprint ""
		(layer "F.Cu")
		(at 148.287486 -390.398254 90)
		(property "Reference" "R1843"
			(at 0 0 90)
			(layer "F.SilkS")
			(hide yes)
			(effects
				(font
					(size 1.27 1.27)
				)
			)
		)
		(property "Value" ""
			(at 0 0 90)
			(layer "F.Fab")
			(effects
				(font
					(size 1.27 1.27)
				)
			)
		)
		(duplicate_pad_numbers_are_jumpers no)
		(fp_line
			(start 0.7874 -0.4064)
			(end 0.7874 0.4064)
			(stroke
				(width 0.1524)
				(type default)
			)
			(layer "F.SilkS")
		)
		(fp_line
			(start -0.7874 -0.4064)
			(end 0.7874 -0.4064)
			(stroke
				(width 0.1524)
				(type default)
			)
			(layer "F.SilkS")
		)
		(fp_line
			(start 0.7874 0.4064)
			(end -0.7874 0.4064)
			(stroke
				(width 0.1524)
				(type default)
			)
			(layer "F.SilkS")
		)
		(fp_line
			(start -0.7874 0.4064)
			(end -0.7874 -0.4064)
			(stroke
				(width 0.1524)
				(type default)
			)
			(layer "F.SilkS")
		)
		(fp_line
			(start -0.12065 -0.305054)
			(end -0.12065 -0.2794)
			(stroke
				(width 0.1)
				(type default)
			)
			(layer "F.Fab")
		)
		(fp_line
			(start -0.67945 -0.305054)
			(end -0.12065 -0.305054)
			(stroke
				(width 0.1)
				(type default)
			)
			(layer "F.Fab")
		)
		(fp_line
			(start 0.67945 -0.3048)
			(end 0.67945 0.3048)
			(stroke
				(width 0.1)
				(type default)
			)
			(layer "F.Fab")
		)
		(fp_line
			(start 0.12065 -0.3048)
			(end 0.67945 -0.3048)
			(stroke
				(width 0.1)
				(type default)
			)
			(layer "F.Fab")
		)
		(fp_line
			(start 0.12065 -0.2794)
			(end 0.12065 -0.3048)
			(stroke
				(width 0.1)
				(type default)
			)
			(layer "F.Fab")
		)
		(fp_line
			(start -0.12065 -0.2794)
			(end 0.12065 -0.2794)
			(stroke
				(width 0.1)
				(type default)
			)
			(layer "F.Fab")
		)
		(fp_line
			(start 0.120396 0.2794)
			(end -0.12065 0.2794)
			(stroke
				(width 0.1)
				(type default)
			)
			(layer "F.Fab")
		)
		(fp_line
			(start -0.12065 0.2794)
			(end -0.12065 0.3048)
			(stroke
				(width 0.1)
				(type default)
			)
			(layer "F.Fab")
		)
		(fp_line
			(start 0.67945 0.3048)
			(end 0.120396 0.3048)
			(stroke
				(width 0.1)
				(type default)
			)
			(layer "F.Fab")
		)
		(fp_line
			(start 0.120396 0.3048)
			(end 0.120396 0.2794)
			(stroke
				(width 0.1)
				(type default)
			)
			(layer "F.Fab")
		)
		(fp_line
			(start -0.12065 0.3048)
			(end -0.67945 0.3048)
			(stroke
				(width 0.1)
				(type default)
			)
			(layer "F.Fab")
		)
		(fp_line
			(start -0.67945 0.3048)
			(end -0.67945 -0.305054)
			(stroke
				(width 0.1)
				(type default)
			)
			(layer "F.Fab")
		)
		(pad "1" smd circle
			(at -0.40005 0 90)
			(size 0 0)
			(layers "F.Cu" "F.Mask" "F.Paste")
			(net "GPU_BASE_STBY_EN_R")
		)
		(pad "2" smd circle
			(at 0.40005 0 90)
			(size 0 0)
			(layers "F.Cu" "F.Mask" "F.Paste")
			(net "GPU_BASE_STBY_EN")
		)
	)
	(footprint ""
		(layer "F.Cu")
		(at 24.792686 -257.148838 -90)
		(property "Reference" "R1260"
			(at 0 0 270)
			(layer "F.SilkS")
			(hide yes)
			(effects
				(font
					(size 1.27 1.27)
				)
			)
		)
		(property "Value" ""
			(at 0 0 270)
			(layer "F.Fab")
			(effects
				(font
					(size 1.27 1.27)
				)
			)
		)
		(duplicate_pad_numbers_are_jumpers no)
		(fp_line
			(start -0.7874 0.4064)
			(end -0.7874 -0.4064)
			(stroke
				(width 0.1524)
				(type default)
			)
			(layer "F.SilkS")
		)
		(fp_line
			(start 0.7874 0.4064)
			(end -0.7874 0.4064)
			(stroke
				(width 0.1524)
				(type default)
			)
			(layer "F.SilkS")
		)
		(fp_line
			(start -0.7874 -0.4064)
			(end 0.7874 -0.4064)
			(stroke
				(width 0.1524)
				(type default)
			)
			(layer "F.SilkS")
		)
		(fp_line
			(start 0.7874 -0.4064)
			(end 0.7874 0.4064)
			(stroke
				(width 0.1524)
				(type default)
			)
			(layer "F.SilkS")
		)
		(fp_line
			(start -0.67945 0.3048)
			(end -0.67945 -0.305054)
			(stroke
				(width 0.1)
				(type default)
			)
			(layer "F.Fab")
		)
		(fp_line
			(start -0.12065 0.3048)
			(end -0.67945 0.3048)
			(stroke
				(width 0.1)
				(type default)
			)
			(layer "F.Fab")
		)
		(fp_line
			(start 0.120396 0.3048)
			(end 0.120396 0.2794)
			(stroke
				(width 0.1)
				(type default)
			)
			(layer "F.Fab")
		)
		(fp_line
			(start 0.67945 0.3048)
			(end 0.120396 0.3048)
			(stroke
				(width 0.1)
				(type default)
			)
			(layer "F.Fab")
		)
		(fp_line
			(start -0.12065 0.2794)
			(end -0.12065 0.3048)
			(stroke
				(width 0.1)
				(type default)
			)
			(layer "F.Fab")
		)
		(fp_line
			(start 0.120396 0.2794)
			(end -0.12065 0.2794)
			(stroke
				(width 0.1)
				(type default)
			)
			(layer "F.Fab")
		)
		(fp_line
			(start -0.12065 -0.2794)
			(end 0.12065 -0.2794)
			(stroke
				(width 0.1)
				(type default)
			)
			(layer "F.Fab")
		)
		(fp_line
			(start 0.12065 -0.2794)
			(end 0.12065 -0.3048)
			(stroke
				(width 0.1)
				(type default)
			)
			(layer "F.Fab")
		)
		(fp_line
			(start 0.12065 -0.3048)
			(end 0.67945 -0.3048)
			(stroke
				(width 0.1)
				(type default)
			)
			(layer "F.Fab")
		)
		(fp_line
			(start 0.67945 -0.3048)
			(end 0.67945 0.3048)
			(stroke
				(width 0.1)
				(type default)
			)
			(layer "F.Fab")
		)
		(fp_line
			(start -0.67945 -0.305054)
			(end -0.12065 -0.305054)
			(stroke
				(width 0.1)
				(type default)
			)
			(layer "F.Fab")
		)
		(fp_line
			(start -0.12065 -0.305054)
			(end -0.12065 -0.2794)
			(stroke
				(width 0.1)
				(type default)
			)
			(layer "F.Fab")
		)
		(pad "1" smd circle
			(at -0.40005 0 270)
			(size 0 0)
			(layers "F.Cu" "F.Mask" "F.Paste")
			(net "P3V3_LED")
		)
		(pad "2" smd circle
			(at 0.40005 0 270)
			(size 0 0)
			(layers "F.Cu" "F.Mask" "F.Paste")
			(net "LED_PEX0_SYS_ERR_N")
		)
	)
	(footprint ""
		(layer "F.Cu")
		(at 204.57541 -121.661682 -90)
		(property "Reference" "PD58"
			(at 4.161282 2.18694 90)
			(unlocked yes)
			(layer "F.SilkS")
			(effects
				(font
					(size 0.7874 0.5842)
					(thickness 0.1524)
				)
				(justify left)
			)
		)
		(property "Value" ""
			(at 0 0 270)
			(layer "F.Fab")
			(effects
				(font
					(size 1.27 1.27)
				)
			)
		)
		(duplicate_pad_numbers_are_jumpers no)
		(fp_line
			(start -3.400044 1.459992)
			(end -3.400044 -1.459992)
			(stroke
				(width 0.1524)
				(type default)
			)
			(layer "F.SilkS")
		)
		(fp_line
			(start 4.107942 1.459992)
			(end -3.400044 1.459992)
			(stroke
				(width 0.1524)
				(type default)
			)
			(layer "F.SilkS")
		)
		(fp_line
			(start -3.400044 -1.459992)
			(end 4.107942 -1.459992)
			(stroke
				(width 0.1524)
				(type default)
			)
			(layer "F.SilkS")
		)
		(fp_line
			(start 4.107942 -1.459992)
			(end 4.107942 1.459992)
			(stroke
				(width 0.1524)
				(type default)
			)
			(layer "F.SilkS")
		)
		(fp_poly
			(pts
				(xy 4.107942 -1.459992) (xy 4.107942 1.459992) (xy 3.308096 1.459992) (xy 3.308096 -1.459992)
			)
			(stroke
				(width 0)
				(type default)
			)
			(fill yes)
			(layer "F.SilkS")
		)
		(fp_line
			(start -2.29997 1.459992)
			(end -2.29997 -1.459992)
			(stroke
				(width 0.1)
				(type default)
			)
			(layer "F.Fab")
		)
		(fp_line
			(start 2.29997 1.459992)
			(end -2.29997 1.459992)
			(stroke
				(width 0.1)
				(type default)
			)
			(layer "F.Fab")
		)
		(fp_line
			(start -2.29997 -1.459992)
			(end 2.29997 -1.459992)
			(stroke
				(width 0.1)
				(type default)
			)
			(layer "F.Fab")
		)
		(fp_line
			(start 2.29997 -1.459992)
			(end 2.29997 1.459992)
			(stroke
				(width 0.1)
				(type default)
			)
			(layer "F.Fab")
		)
		(fp_text user "-"
			(at 5.4102 0.29845 90)
			(unlocked yes)
			(layer "F.SilkS")
			(effects
				(font
					(size 1.905 1.4224)
					(thickness 0.1524)
				)
				(justify left)
			)
		)
		(fp_text user "+"
			(at -4.7752 -0.12065 270)
			(unlocked yes)
			(layer "F.SilkS")
			(effects
				(font
					(size 1.905 1.4224)
					(thickness 0.1524)
				)
				(justify left)
			)
		)
		(fp_text user "-"
			(at 5.4102 0.29845 90)
			(unlocked yes)
			(layer "F.Fab")
			(effects
				(font
					(size 1.905 1.4224)
					(thickness 0.1524)
				)
				(justify left)
			)
		)
		(fp_text user "+"
			(at -4.7752 -0.12065 270)
			(unlocked yes)
			(layer "F.Fab")
			(effects
				(font
					(size 1.905 1.4224)
					(thickness 0.1524)
				)
				(justify left)
			)
		)
		(pad "A" smd rect
			(at -1.999996 0)
			(size 1.7018 2.5146)
			(layers "F.Cu" "F.Mask" "F.Paste")
			(net "GND")
		)
		(pad "C" smd rect
			(at 1.999996 0)
			(size 1.7018 2.5146)
			(layers "F.Cu" "F.Mask" "F.Paste")
			(net "P3V3_NIC3")
		)
	)
)
